FILE_TYPE = CONNECTIVITY;
{Allegro Design Entry HDL 17.2-2016 S081 (4005846) 1/11/2022}
"PAGE_NUMBER" = 265;
0"NC";
1"PVCCFA_EHV_CPU0_PVCC";
2"SW_P12V_PVCCINFAON_CPU0_FLT\g";
3"PVCCD_HV_CPU0\g";
4"PVCCD_HV_CPU0\g";
5"GND\g";
6"GND\g";
7"GND\g";
8"GND\g";
9"GND\g";
10"GND\g";
11"GND\g";
12"GND\g";
13"SW_PVCCD_HV_CPU0_SW1";
14"SW_PVCCD_HV_CPU0_BOOTR1"CDS_PHYS_NET_NAME"SW_PVCCD_HV_CPU0_BOOTR1";
15"SW_PVCCD_HV_CPU0_BOOT1_R";
16"SW_PVCCD_HV_CPU0_BOOT1"CDS_PHYS_NET_NAME"SW_PVCCD_HV_CPU0_BOOT1";
17"PVCCD_HV_CPU0_VOS";
18"PVCCD_HV_CPU0_VDD1";
19"PVCCD_HV_CPU0_ACSP1";
20"PVCCD_HV_CPU0_APWM1";
21"PVCCD_HV_CPU0_ATSEN";
22"PVCCD_HV_CPU0_VREF"CDS_PHYS_NET_NAME"PVCCD_HV_CPU0_VREF";
23"PVCCD_HV_CPU0_LSET1";
%"UNIVERSAL_GND"
"1","(-9000,1625)","0","logical_power","I1";
;
HDL_POWER"GND"
CDS_LIB"logical_power";
"A"5;
%"UNIVERSAL_GND"
"1","(-8225,2125)","0","logical_power","I10";
;
HDL_POWER"GND"
CDS_LIB"logical_power";
"A"7;
%"Q_CAP"
"1","(-8225,2375)","0","pure_quanta","I11";
;
PART_NUMBER"CH5222KEB01"
PACK_TYPE"C0402"
MATERIAL"X6S"
VOLTAGE"10V"
TOLERANCE"10%"
VALUE"2.2UF"
LOCATION"PC633"
CDS_LIB"pure_quanta"
LOCATION"PC633"
$SEC"1"
CDS_SEC"1";
"B"
$PN"2"7;
"A"
$PN"1"18;
%"Q_RES"
"2","(-8225,2775)","0","pure_quanta","I12";
;
PART_NUMBER"CS-2202FB01"
WATTAGE"1/16W"
TOLERANCE"1%"
VALUE"2.2"
PACK_TYPE"0402LF"
MATERIAL"CHIP"
LOCATION"PR380"
CDS_LIB"pure_quanta"
LOCATION"PR380"
$SEC"1"
CDS_SEC"1";
"A"
$PN"1"1;
"B"
$PN"2"18;
%"UNIVERSAL_GND"
"1","(-7575,2575)","0","logical_power","I13";
;
HDL_POWER"GND"
CDS_LIB"logical_power";
"A"8;
%"Q_CAP"
"1","(-7575,2800)","0","pure_quanta","I14";
;
PART_NUMBER"CH5222KEB01"
PACK_TYPE"C0402"
VALUE"2.2UF"
VOLTAGE"10V"
MATERIAL"X6S"
TOLERANCE"10%"
LOCATION"PC2948"
CDS_LIB"pure_quanta"
$SEC"1"
CDS_SEC"1";
"B"
$PN"2"8;
"A"
$PN"1"1;
%"VCC15"
"1","(-8225,3350)","0","logical_power","I15";
;
HDL_POWER"PVCCFA_EHV_CPU0_PVCC"
CDS_LIB"logical_power";
"A"1;
%"UNIVERSAL_GND"
"1","(-6050,1200)","0","logical_power","I16";
;
HDL_POWER"GND"
CDS_LIB"logical_power";
"A"9;
%"Q_RES"
"1","(-5150,1675)","0","pure_quanta","I17";
;
PART_NUMBER"CS00002JB13"
MATERIAL"CHIP"
WATTAGE"1/16W"
PACK_TYPE"0402LF"
TOLERANCE"5%"
VALUE"0"
LOCATION"PR1785"
CDS_LIB"pure_quanta"
$SEC"1"
CDS_SEC"1";
"B"
$PN"2"4;
"A"
$PN"1"17;
%"Q_CAP"
"1","(-5900,2825)","0","pure_quanta","I18";
;
PART_NUMBER"TMP_QCH2336K1B12"
TOLERANCE"10%"
VOLTAGE"50V"
PACK_TYPE"0402"
MATERIAL"X7R"
VALUE"3300PF"
LOCATION"PC634"
CDS_LIB"pure_quanta"
LOCATION"PC634"
$SEC"1"
CDS_SEC"1";
"B"
$PN"2"10;
"A"
$PN"1"2;
%"Q_RES"
"1","(-5450,2375)","0","pure_quanta","I19";
;
PART_NUMBER"CS-3302FB01"
MATERIAL"CHIP"
WATTAGE"1/16W"
PACK_TYPE"0402LF"
TOLERANCE"1%"
VALUE"3.3"
LOCATION"PR1784"
CDS_LIB"pure_quanta"
$SEC"1"
CDS_SEC"1";
"B"
$PN"2"15;
"A"
$PN"1"16;
%"UNIVERSAL_GND"
"1","(-8775,1100)","0","logical_power","I2";
;
HDL_POWER"GND"
CDS_LIB"logical_power";
"A"6;
%"Q_CAP"
"1","(-5500,2825)","0","pure_quanta","I20";
;
PART_NUMBER"CH5103KEB01"
MATERIAL"X6S"
PACK_TYPE"C0402"
VOLTAGE"16V"
VALUE"1UF"
TOLERANCE"10%"
LOCATION"PC635"
CDS_LIB"pure_quanta"
LOCATION"PC635"
$SEC"1"
CDS_SEC"1";
"B"
$PN"2"10;
"A"
$PN"1"2;
%"Q_CAP"
"1","(-5100,2825)","0","pure_quanta","I21";
;
PART_NUMBER"CH6223MEA01"
TOLERANCE"20%"
PACK_TYPE"C0805"
VOLTAGE"16V"
VALUE"22UF"
MATERIAL"X6S"
LOCATION"PC637"
CDS_LIB"pure_quanta"
LOCATION"PC637"
$SEC"1"
CDS_SEC"1";
"B"
$PN"2"10;
"A"
$PN"1"2;
%"Q_CAP"
"1","(-4675,2200)","2","pure_quanta","I22";
;
PART_NUMBER"CH4106K1B01"
VALUE"100NF"
MATERIAL"X7R"
PACK_TYPE"C0402"
VOLTAGE"50V"
TOLERANCE"10%"
LOCATION"PC636"
CDS_LIB"pure_quanta"
$SEC"1"
CDS_SEC"1";
"B"
$PN"2"14;
"A"
$PN"1"15;
%"Q_CAP"
"1","(-4700,2825)","0","pure_quanta","I23";
;
PART_NUMBER"CH6223MEA01"
TOLERANCE"20%"
MATERIAL"X6S"
PACK_TYPE"C0805"
VALUE"22UF"
VOLTAGE"16V"
LOCATION"PC638"
CDS_LIB"pure_quanta"
LOCATION"PC638"
$SEC"1"
CDS_SEC"1";
"B"
$PN"2"10;
"A"
$PN"1"2;
%"Q_CAP"
"1","(-3750,1725)","0","pure_quanta","I24";
;
PART_NUMBER"CH4106K1B01"
TOLERANCE"10%"
VOLTAGE"50V"
VALUE"100NF"
PACK_TYPE"C0402"
MATERIAL"X7R"
LOCATION"PC639"
CDS_LIB"pure_quanta"
LOCATION"PC639"
$SEC"1"
CDS_SEC"1";
"B"
$PN"2"12;
"A"
$PN"1"4;
%"Q_CAP"
"1","(-3350,1725)","0","pure_quanta","I25";
;
PART_NUMBER"CH622KMEA03"
TOLERANCE"20%"
PACK_TYPE"C0805"
MATERIAL"X6S"
VALUE"22UF"
VOLTAGE"4V"
LOCATION"PC641"
CDS_LIB"pure_quanta"
LOCATION"PC641"
$SEC"1"
CDS_SEC"1";
"B"
$PN"2"12;
"A"
$PN"1"4;
%"Q_CAPP"
"1","(-3150,300)","0","pure_quanta","I26";
;
PART_NUMBER"CH733RY8807"
PACK_TYPE"SMLF"
VOLTAGE"2V"
VALUE"330UF"
TOLERANCE"35%"
MATERIAL"SPCAP"
LOCATION"PC1910"
CDS_LIB"pure_quanta"
$SEC"1"
CDS_SEC"1";
"A"
$PN"1"3;
"B"
$PN"2"11;
%"Q_CAPP"
"1","(-2675,275)","0","pure_quanta","I27";
;
PART_NUMBER"CC7560JMD16"
PACK_TYPE"THLF"
VALUE"560UF"
TOLERANCE"20%"
MATERIAL"OSCON"
VOLTAGE"2.5V"
LOCATION"PC1644"
CDS_LIB"pure_quanta"
$SEC"1"
CDS_SEC"1";
"A"
$PN"1"3;
"B"
$PN"2"11;
%"Q_CAP"
"1","(-2825,1725)","0","pure_quanta","I28";
;
PART_NUMBER"CH622KMEA03"
TOLERANCE"20%"
VOLTAGE"4V"
VALUE"22UF"
PACK_TYPE"C0805"
MATERIAL"X6S"
LOCATION"PC642"
CDS_LIB"pure_quanta"
LOCATION"PC642"
$SEC"1"
CDS_SEC"1";
"B"
$PN"2"12;
"A"
$PN"1"4;
%"Q_CAP"
"1","(-2275,1725)","0","pure_quanta","I29";
;
PART_NUMBER"CH622KMEA03"
TOLERANCE"20%"
VOLTAGE"4V"
PACK_TYPE"C0805"
VALUE"22UF"
MATERIAL"X6S"
LOCATION"PC1"
CDS_LIB"pure_quanta"
LOCATION"PC1"
$SEC"1"
CDS_SEC"1";
"B"
$PN"2"12;
"A"
$PN"1"4;
%"Q_RES"
"2","(-8775,1325)","2","pure_quanta","I3";
;
PART_NUMBER"CS28872FB01"
TOLERANCE"1%"
WATTAGE"1/16W"
MATERIAL"EMPTY"
PACK_TYPE"0402LF"
VALUE"8.87K"
LOCATION"PR2718"
CDS_LIB"pure_quanta"
$SEC"1"
CDS_SEC"1";
"A"
$PN"1"23;
"B"
$PN"2"6;
%"Q_INDUCTOR"
"1","(-4200,1950)","0","pure_quanta","I30";
;
PART_NUMBER"CV+12^0EZ03"
VALUE"120NH/69A"
MATERIAL"IND"
PACK_TYPE"SMLF"
LOCATION"PL35"
CDS_LIB"pure_quanta"
NEEDS_NO_SIZE"TRUE"
$SEC"1"
CDS_SEC"1";
"1"
$PN"1"13;
"2"
$PN"2"4;
%"UNIVERSAL_GND"
"1","(-4100,2400)","0","logical_power","I31";
;
HDL_POWER"GND"
CDS_LIB"logical_power";
"A"10;
%"VCC15"
"1","(-4100,3200)","0","logical_power","I32";
;
HDL_POWER"SW_P12V_PVCCINFAON_CPU0_FLT"
CDS_LIB"logical_power";
"A"2;
%"UNIVERSAL_GND"
"1","(-2175,-50)","0","logical_power","I33";
;
HDL_POWER"GND"
CDS_LIB"logical_power";
"A"11;
%"Q_CAPP"
"1","(-2175,275)","0","pure_quanta","I34";
;
PART_NUMBER"CC7560JMD16"
PACK_TYPE"THLF"
VALUE"560UF"
TOLERANCE"20%"
MATERIAL"OSCON"
VOLTAGE"2.5V"
LOCATION"PC1645"
CDS_LIB"pure_quanta"
$SEC"1"
CDS_SEC"1";
"A"
$PN"1"3;
"B"
$PN"2"11;
%"VCC15"
"1","(-2175,600)","0","logical_power","I35";
;
HDL_POWER"PVCCD_HV_CPU0"
CDS_LIB"logical_power";
"A"3;
%"UNIVERSAL_GND"
"1","(-1825,1350)","0","logical_power","I36";
;
HDL_POWER"GND"
CDS_LIB"logical_power";
"A"12;
%"Q_RES"
"2","(-1825,1725)","0","pure_quanta","I37";
;
PART_NUMBER"CS14992FB06"
VALUE"499"
TOLERANCE"1%"
MATERIAL"CHIP"
PACK_TYPE"0402LF"
WATTAGE"1/16W"
LOCATION"PR4237"
BOM_COST"VR_PCH"
CDS_LIB"pure_quanta"
$SEC"1"
CDS_SEC"1";
"A"
$PN"1"4;
"B"
$PN"2"12;
%"VCC15"
"1","(-1825,2075)","0","logical_power","I38";
;
HDL_POWER"PVCCD_HV_CPU0"
CDS_LIB"logical_power";
"A"4;
%"Q_CAP"
"2","(-8050,1750)","0","pure_quanta","I7";
;
PART_NUMBER"CH4104K1B00"
PACK_TYPE"0402"
VOLTAGE"25V"
VALUE"0.1UF"
TOLERANCE"10%"
MATERIAL"X7R"
LOCATION"PC1354"
CDS_LIB"pure_quanta"
$SEC"1"
CDS_SEC"1";
"A"
$PN"1"5;
"B"
$PN"2"22;
%"ISL99390FRZTR5935"
"1","(-6700,1925)","0","pure_quanta","I8";
;
PART_NUMBER"AL099390004"
PART_TYPE"SMLF"
VALUE"ISL99390FRZ-TR5935"
MATERIAL"IC"
LOCATION"PU36"
SEC_TYPE""
CDS_LIB"pure_quanta"
NEEDS_NO_SIZE"TRUE"
CDS_LMAN_SYM_OUTLINE"-300,700,250,-650"
SEC"1";
"PGND2"
$PN"7_9-20_24"9;
"GL2"
$PN"41"0;
"GL1"
$PN"6"0;
"DNC"
$PN"31"0;
"EN"
$PN"35"18;
"PGND3"
$PN"40"9;
"VOS"
$PN"1"17;
"VIN2"
$PN"30"2;
"PGND1"
$PN"5"9;
"SW"
$PN"10_19"13;
"LSET"
$PN"37"23;
"IOUT"
$PN"38"19;
"TOUT_FLT"
$PN"36"21;
"PVCC"
$PN"4"1;
"PHASE"
$PN"32"14;
"VIN1"
$PN"25_29"2;
"BOOT"
$PN"33"16;
"AGND"
$PN"2"9;
"VCC"
$PN"3"18;
"REFIN"
$PN"39"22;
"PWM"
$PN"34"20;
END.
